# S9S_MB_2U (Grand Teton) — schematic netlist excerpt (pin names and nets, part order shuffled) for the footprints in the layout excerpt that follows; sources: Cadence DE-HDL packaged netlist, KiCad conversion of 03242023_DA0F0TMBIJ0_F0T_Motherboard_J_brd_V01_OCP.brd

Q124  MOSFET_NCH_DUAL  PJT138K IC  pkg SOT363XD  page 156
  S1  = GND
  G1  = P3V3_OCP_EN_1_R
  D2  = P3V3_OCP_UV_1_R1
  S2  = GND
  G2  = P3V3_OCP_1_EN_G
  D1  = P3V3_OCP_1_EN_G

R4786  Q_RES  10K 1% EMPTY  pkg 0402LF  page 307 : A = P3V3_AUX ; B = DSW_PWROK_P2V5_COMP

(kicad_pcb
	(version 20260206)
	(generator "pcbnew")
	(generator_version "10.0")
	(general
		(thickness 1.6)
		(legacy_teardrops no)
	)
	(paper "A4")
	(title_block
		(title "03242023_DA0F0TMBIJ0_F0T_Motherboard_J_brd_V01_OCP.brd")
		(comment 1 "Grand Teton / footprints 3825-3826 of 6105")
	)
	(layers
		(0 "F.Cu" signal "TOP")
		(4 "In1.Cu" signal "GND")
		(6 "In2.Cu" signal "IN1")
		(8 "In3.Cu" signal "GND1")
		(10 "In4.Cu" signal "IN2")
		(12 "In5.Cu" signal "GND2")
		(14 "In6.Cu" signal "IN3")
		(16 "In7.Cu" signal "GND3")
		(18 "In8.Cu" signal "VCC")
		(20 "In9.Cu" signal "VCC1")
		(22 "In10.Cu" signal "GND4")
		(24 "In11.Cu" signal "IN4")
		(26 "In12.Cu" signal "GND5")
		(28 "In13.Cu" signal "IN5")
		(30 "In14.Cu" signal "GND6")
		(32 "In15.Cu" signal "IN6")
		(34 "In16.Cu" signal "GND7")
		(2 "B.Cu" signal "BOTTOM")
		(9 "F.Adhes" user "F.Adhesive")
		(11 "B.Adhes" user "B.Adhesive")
		(13 "F.Paste" user "Package Geometry/Pastemask Top")
		(15 "B.Paste" user "Package Geometry/Pastemask Bottom")
		(5 "F.SilkS" user "Ref Des/Silkscreen Top")
		(7 "B.SilkS" user "Ref Des/Silkscreen Bottom")
		(1 "F.Mask" user "Board Geometry/Soldermask Top")
		(3 "B.Mask" user "Board Geometry/Soldermask Bottom")
		(17 "Dwgs.User" user "User.Drawings")
		(19 "Cmts.User" user "User.Comments")
		(21 "Eco1.User" user "User.Eco1")
		(23 "Eco2.User" user "User.Eco2")
		(25 "Edge.Cuts" user "Board Geometry/Outline")
		(27 "Margin" user)
		(31 "F.CrtYd" user "Package Geometry/Place Bound Top")
		(29 "B.CrtYd" user "Package Geometry/Place Bound Bottom")
		(35 "F.Fab" user "Ref Des/Assembly Top")
		(33 "B.Fab" user "Ref Des/Assembly Bottom")
	)
	(footprint ""
		(layer "F.Cu")
		(at 461.53705 -41.002458)
		(property "Reference" "Q124"
			(at -3.73507 -2.576576 0)
			(unlocked yes)
			(layer "F.SilkS")
			(effects
				(font
					(size 0.7874 0.5842)
					(thickness 0.1524)
				)
				(justify left)
			)
		)
		(property "Value" ""
			(at 0 0 0)
			(layer "F.Fab")
			(effects
				(font
					(size 1.27 1.27)
				)
			)
		)
		(duplicate_pad_numbers_are_jumpers no)
		(fp_line
			(start -1.332738 -1.100074)
			(end -0.4826 -1.100074)
			(stroke
				(width 0.1524)
				(type default)
			)
			(layer "F.SilkS")
		)
		(fp_line
			(start -1.332738 1.100074)
			(end -1.332738 -1.100074)
			(stroke
				(width 0.1524)
				(type default)
			)
			(layer "F.SilkS")
		)
		(fp_line
			(start -0.4826 -1.100074)
			(end 0 -0.541274)
			(stroke
				(width 0.1524)
				(type default)
			)
			(layer "F.SilkS")
		)
		(fp_line
			(start 0 -0.541274)
			(end 0.4826 -1.100074)
			(stroke
				(width 0.1524)
				(type default)
			)
			(layer "F.SilkS")
		)
		(fp_line
			(start 0.4826 -1.100074)
			(end 1.332738 -1.100074)
			(stroke
				(width 0.1524)
				(type default)
			)
			(layer "F.SilkS")
		)
		(fp_line
			(start 1.332738 -1.100074)
			(end 1.332738 1.100074)
			(stroke
				(width 0.1524)
				(type default)
			)
			(layer "F.SilkS")
		)
		(fp_line
			(start 1.332738 1.100074)
			(end -1.332738 1.100074)
			(stroke
				(width 0.1524)
				(type default)
			)
			(layer "F.SilkS")
		)
		(fp_poly
			(pts
				(xy -0.672846 -2.01422) (xy -1.023874 -1.312164) (xy -1.374902 -2.01422)
			)
			(stroke
				(width 0)
				(type default)
			)
			(fill yes)
			(layer "F.SilkS")
		)
		(fp_line
			(start -0.674878 -1.100074)
			(end 0.674878 -1.100074)
			(stroke
				(width 0.1)
				(type default)
			)
			(layer "F.Fab")
		)
		(fp_line
			(start -0.674878 1.100074)
			(end -0.674878 -1.100074)
			(stroke
				(width 0.1)
				(type default)
			)
			(layer "F.Fab")
		)
		(fp_line
			(start 0.674878 -1.100074)
			(end 0.674878 1.100074)
			(stroke
				(width 0.1)
				(type default)
			)
			(layer "F.Fab")
		)
		(fp_line
			(start 0.674878 1.100074)
			(end -0.674878 1.100074)
			(stroke
				(width 0.1)
				(type default)
			)
			(layer "F.Fab")
		)
		(fp_poly
			(pts
				(xy -2.2352 -0.298958) (xy -2.2352 -1.001014) (xy -1.533144 -0.649986)
			)
			(stroke
				(width 0)
				(type default)
			)
			(fill yes)
			(layer "F.Fab")
		)
		(pad "1" smd rect
			(at -0.94996 -0.649986 90)
			(size 0.4318 0.508)
			(layers "F.Cu" "F.Mask" "F.Paste")
			(net "GND")
		)
		(pad "2" smd rect
			(at -0.94996 0 90)
			(size 0.4318 0.508)
			(layers "F.Cu" "F.Mask" "F.Paste")
			(net "P3V3_OCP_EN_1_R")
		)
		(pad "3" smd rect
			(at -0.94996 0.649986 90)
			(size 0.4318 0.508)
			(layers "F.Cu" "F.Mask" "F.Paste")
			(net "P3V3_OCP_UV_1_R1")
		)
		(pad "4" smd rect
			(at 0.94996 0.649986 90)
			(size 0.4318 0.508)
			(layers "F.Cu" "F.Mask" "F.Paste")
			(net "GND")
		)
		(pad "5" smd rect
			(at 0.94996 0 90)
			(size 0.4318 0.508)
			(layers "F.Cu" "F.Mask" "F.Paste")
			(net "P3V3_OCP_1_EN_G")
		)
		(pad "6" smd rect
			(at 0.94996 -0.649986 90)
			(size 0.4318 0.508)
			(layers "F.Cu" "F.Mask" "F.Paste")
			(net "P3V3_OCP_1_EN_G")
		)
	)
	(footprint ""
		(layer "F.Cu")
		(at 309.372 -23.7744 180)
		(property "Reference" "R4786"
			(at 0 0 180)
			(layer "F.SilkS")
			(hide yes)
			(effects
				(font
					(size 1.27 1.27)
				)
			)
		)
		(property "Value" ""
			(at 0 0 180)
			(layer "F.Fab")
			(effects
				(font
					(size 1.27 1.27)
				)
			)
		)
		(duplicate_pad_numbers_are_jumpers no)
		(fp_line
			(start 0.7874 0.4064)
			(end -0.7874 0.4064)
			(stroke
				(width 0.1524)
				(type default)
			)
			(layer "F.SilkS")
		)
		(fp_line
			(start 0.7874 -0.4064)
			(end 0.7874 0.4064)
			(stroke
				(width 0.1524)
				(type default)
			)
			(layer "F.SilkS")
		)
		(fp_line
			(start -0.7874 0.4064)
			(end -0.7874 -0.4064)
			(stroke
				(width 0.1524)
				(type default)
			)
			(layer "F.SilkS")
		)
		(fp_line
			(start -0.7874 -0.4064)
			(end 0.7874 -0.4064)
			(stroke
				(width 0.1524)
				(type default)
			)
			(layer "F.SilkS")
		)
		(fp_line
			(start 0.67945 0.3048)
			(end 0.120396 0.3048)
			(stroke
				(width 0.1)
				(type default)
			)
			(layer "F.Fab")
		)
		(fp_line
			(start 0.67945 -0.3048)
			(end 0.67945 0.3048)
			(stroke
				(width 0.1)
				(type default)
			)
			(layer "F.Fab")
		)
		(fp_line
			(start 0.12065 -0.2794)
			(end 0.12065 -0.3048)
			(stroke
				(width 0.1)
				(type default)
			)
			(layer "F.Fab")
		)
		(fp_line
			(start 0.12065 -0.3048)
			(end 0.67945 -0.3048)
			(stroke
				(width 0.1)
				(type default)
			)
			(layer "F.Fab")
		)
		(fp_line
			(start 0.120396 0.3048)
			(end 0.120396 0.2794)
			(stroke
				(width 0.1)
				(type default)
			)
			(layer "F.Fab")
		)
		(fp_line
			(start 0.120396 0.2794)
			(end -0.12065 0.2794)
			(stroke
				(width 0.1)
				(type default)
			)
			(layer "F.Fab")
		)
		(fp_line
			(start -0.12065 0.3048)
			(end -0.67945 0.3048)
			(stroke
				(width 0.1)
				(type default)
			)
			(layer "F.Fab")
		)
		(fp_line
			(start -0.12065 0.2794)
			(end -0.12065 0.3048)
			(stroke
				(width 0.1)
				(type default)
			)
			(layer "F.Fab")
		)
		(fp_line
			(start -0.12065 -0.2794)
			(end 0.12065 -0.2794)
			(stroke
				(width 0.1)
				(type default)
			)
			(layer "F.Fab")
		)
		(fp_line
			(start -0.12065 -0.305054)
			(end -0.12065 -0.2794)
			(stroke
				(width 0.1)
				(type default)
			)
			(layer "F.Fab")
		)
		(fp_line
			(start -0.67945 0.3048)
			(end -0.67945 -0.305054)
			(stroke
				(width 0.1)
				(type default)
			)
			(layer "F.Fab")
		)
		(fp_line
			(start -0.67945 -0.305054)
			(end -0.12065 -0.305054)
			(stroke
				(width 0.1)
				(type default)
			)
			(layer "F.Fab")
		)
		(pad "1" smd circle
			(at -0.40005 0 180)
			(size 0 0)
			(layers "F.Cu" "F.Mask" "F.Paste")
			(net "P3V3_AUX")
		)
		(pad "2" smd circle
			(at 0.40005 0 180)
			(size 0 0)
			(layers "F.Cu" "F.Mask" "F.Paste")
			(net "DSW_PWROK_P2V5_COMP")
		)
	)
)
